(kicad_pcb
	(version 20260206)
	(generator "pcbnew")
	(generator_version "10.0")
	(general
		(thickness 1.6)
		(legacy_teardrops no)
	)
	(paper "A4")
	(title_block
		(title "Bryce Canyon_R.DPB_16317-1_OCP.brd")
		(comment 1 "Bryce Canyon / footprints 230-237 of 2099")
	)
	(layers
		(0 "F.Cu" signal "TOP")
		(4 "In1.Cu" signal "L2GND")
		(6 "In2.Cu" signal "L3")
		(8 "In3.Cu" signal "L4VCC")
		(10 "In4.Cu" signal "L5VCC")
		(12 "In5.Cu" signal "L6")
		(14 "In6.Cu" signal "L7GND")
		(2 "B.Cu" signal "BOTTOM")
		(9 "F.Adhes" user "F.Adhesive")
		(11 "B.Adhes" user "B.Adhesive")
		(13 "F.Paste" user "Package Geometry/Pastemask Top")
		(15 "B.Paste" user "Package Geometry/Pastemask Bottom")
		(5 "F.SilkS" user "Ref Des/Silkscreen Top")
		(7 "B.SilkS" user "Ref Des/Silkscreen Bottom")
		(1 "F.Mask" user "Board Geometry/Soldermask Top")
		(3 "B.Mask" user "Board Geometry/Soldermask Bottom")
		(17 "Dwgs.User" user "User.Drawings")
		(19 "Cmts.User" user "User.Comments")
		(21 "Eco1.User" user "User.Eco1")
		(23 "Eco2.User" user "User.Eco2")
		(25 "Edge.Cuts" user "Board Geometry/Outline")
		(27 "Margin" user)
		(31 "F.CrtYd" user "Package Geometry/Place Bound Top")
		(29 "B.CrtYd" user "Package Geometry/Place Bound Bottom")
		(35 "F.Fab" user "Ref Des/Assembly Top")
		(33 "B.Fab" user "Ref Des/Assembly Bottom")
	)
	(footprint ""
		(layer "F.Cu")
		(at 22.987 -249.555 90)
		(property "Reference" "R910"
			(at 0 0 90)
			(layer "F.SilkS")
			(hide yes)
			(effects
				(font
					(size 1.27 1.27)
				)
			)
		)
		(property "Value" "4K7R2F-GP"
			(at 0.064008 -3.993896 90)
			(unlocked yes)
			(layer "F.Fab")
			(hide yes)
			(effects
				(font
					(size 1.016 1.016)
					(thickness 0.1524)
				)
			)
		)
		(property "Device Type" "R402H16"
			(at 0.064008 -5.517896 90)
			(unlocked yes)
			(layer "F.Fab")
			(hide yes)
			(effects
				(font
					(size 1.016 1.016)
					(thickness 0.1524)
				)
			)
		)
		(duplicate_pad_numbers_are_jumpers no)
		(fp_line
			(start 0.508 -0.9398)
			(end -0.508 -0.9398)
			(stroke
				(width 0.1524)
				(type default)
			)
			(layer "F.SilkS")
		)
		(fp_line
			(start -0.508 -0.9398)
			(end -0.508 0.9398)
			(stroke
				(width 0.1524)
				(type default)
			)
			(layer "F.SilkS")
		)
		(fp_rect
			(start -0.508 0.9398)
			(end 0.508 -0.9398)
			(stroke
				(width 0)
				(type default)
			)
			(fill no)
			(layer "F.CrtYd")
		)
		(fp_rect
			(start -0.508 0.9398)
			(end 0.508 -0.9398)
			(stroke
				(width 0)
				(type default)
			)
			(fill no)
			(layer "F.Fab")
		)
		(pad "1" smd custom
			(at 0 -0.4445 90)
			(size 0.1397 0.1397)
			(layers "F.Cu" "F.Mask" "F.Paste")
			(net "SW_PWR_R_HDD0")
			(options
				(clearance outline)
				(anchor circle)
			)
			(primitives
				(gr_poly
					(pts
						(arc
							(start -0.1778 -0.2794)
							(mid -0.249642 -0.249642)
							(end -0.2794 -0.1778)
						)
						(arc
							(start -0.2794 0.1778)
							(mid -0.249642 0.249642)
							(end -0.1778 0.2794)
						)
						(arc
							(start 0.1778 0.2794)
							(mid 0.249642 0.249642)
							(end 0.2794 0.1778)
						)
						(arc
							(start 0.2794 -0.1778)
							(mid 0.249642 -0.249642)
							(end 0.1778 -0.2794)
						)
					)
					(width 0)
					(fill yes)
				)
			)
		)
		(pad "2" smd custom
			(at 0 0.4445 90)
			(size 0.1397 0.1397)
			(layers "F.Cu" "F.Mask" "F.Paste")
			(net "GND")
			(options
				(clearance outline)
				(anchor circle)
			)
			(primitives
				(gr_poly
					(pts
						(arc
							(start -0.1778 -0.2794)
							(mid -0.249642 -0.249642)
							(end -0.2794 -0.1778)
						)
						(arc
							(start -0.2794 0.1778)
							(mid -0.249642 0.249642)
							(end -0.1778 0.2794)
						)
						(arc
							(start 0.1778 0.2794)
							(mid 0.249642 0.249642)
							(end 0.2794 0.1778)
						)
						(arc
							(start 0.2794 -0.1778)
							(mid 0.249642 -0.249642)
							(end 0.1778 -0.2794)
						)
					)
					(width 0)
					(fill yes)
				)
			)
		)
	)
	(footprint ""
		(layer "F.Cu")
		(at 269.80007 -378.000006 90)
		(property "Reference" "Q208"
			(at 0 0 90)
			(layer "F.SilkS")
			(hide yes)
			(effects
				(font
					(size 1.27 1.27)
				)
			)
		)
		(property "Value" "SENSOR-2P-10-GP"
			(at -0.0127 -6.0325 90)
			(unlocked yes)
			(layer "F.Fab")
			(hide yes)
			(effects
				(font
					(size 1.016 1.016)
					(thickness 0.1524)
				)
			)
		)
		(property "Device Type" "SNR2N4036H168"
			(at -0.0127 -7.5565 90)
			(unlocked yes)
			(layer "F.Fab")
			(hide yes)
			(effects
				(font
					(size 1.016 1.016)
					(thickness 0.1524)
				)
			)
		)
		(duplicate_pad_numbers_are_jumpers no)
		(fp_line
			(start 2.2479 -2.1336)
			(end 2.2479 2.0574)
			(stroke
				(width 0.1524)
				(type default)
			)
			(layer "F.SilkS")
		)
		(fp_line
			(start -2.2479 -2.1336)
			(end 2.2479 -2.1336)
			(stroke
				(width 0.1524)
				(type default)
			)
			(layer "F.SilkS")
		)
		(fp_line
			(start 2.2479 2.0574)
			(end -2.2479 2.0574)
			(stroke
				(width 0.1524)
				(type default)
			)
			(layer "F.SilkS")
		)
		(fp_line
			(start -2.2479 2.0574)
			(end -2.2479 -2.1336)
			(stroke
				(width 0.1524)
				(type default)
			)
			(layer "F.SilkS")
		)
		(fp_poly
			(pts
				(xy -1.8796 -2.7178) (xy -1.8796 -2.2098) (xy -1.3716 -2.2098) (xy -1.3716 -2.7178)
			)
			(stroke
				(width 0)
				(type default)
			)
			(fill yes)
			(layer "F.SilkS")
		)
		(fp_rect
			(start -1.9939 1.8034)
			(end 1.9939 -1.8034)
			(stroke
				(width 0)
				(type default)
			)
			(fill no)
			(layer "F.CrtYd")
		)
		(fp_poly
			(pts
				(xy -2.5019 2.3114) (xy -2.5019 -2.3876) (xy 2.5019 -2.3876) (xy 2.5019 -0.4445) (xy 1.9939 -0.4445)
				(xy 1.9939 -1.8034) (xy -1.9939 -1.8034) (xy -1.9939 1.8034) (xy 1.9939 1.8034) (xy 1.9939 -0.4318)
				(xy 2.5019 -0.4318) (xy 2.5019 2.3114)
			)
			(stroke
				(width 0)
				(type default)
			)
			(fill no)
			(layer "F.CrtYd")
		)
		(fp_rect
			(start -2.5019 2.3114)
			(end 2.5019 -2.3876)
			(stroke
				(width 0)
				(type default)
			)
			(fill no)
			(layer "F.Fab")
		)
		(fp_text user "E"
			(at 2.466594 -0.28067 90)
			(unlocked yes)
			(layer "F.SilkS")
			(effects
				(font
					(size 1.016 1.016)
					(thickness 0.1524)
				)
				(justify left)
			)
		)
		(fp_text user "C"
			(at -3.426206 -0.20447 90)
			(unlocked yes)
			(layer "F.SilkS")
			(effects
				(font
					(size 1.016 1.016)
					(thickness 0.1524)
				)
				(justify left)
			)
		)
		(pad "C" smd rect
			(at -1.27 -0.374904 90)
			(size 1.1938 2.9972)
			(layers "F.Cu" "F.Mask" "F.Paste")
			(net "IR_SWITCH_C")
		)
		(pad "E" smd rect
			(at 1.27 -0.374904 90)
			(size 1.1938 2.9972)
			(layers "F.Cu" "F.Mask" "F.Paste")
			(net "IR_SWITCH_E")
		)
	)
	(footprint ""
		(layer "F.Cu")
		(at 362.966 -44.958 180)
		(property "Reference" "C437"
			(at 0 0 180)
			(layer "F.SilkS")
			(hide yes)
			(effects
				(font
					(size 1.27 1.27)
				)
			)
		)
		(property "Value" "SC4D7U25V5KX-1-GP"
			(at -0.0762 -6.1214 180)
			(unlocked yes)
			(layer "F.Fab")
			(hide yes)
			(effects
				(font
					(size 1.016 1.016)
					(thickness 0.1524)
				)
			)
		)
		(property "Device Type" "C805H58"
			(at -0.0762 -8.1534 180)
			(unlocked yes)
			(layer "F.Fab")
			(hide yes)
			(effects
				(font
					(size 1.016 1.016)
					(thickness 0.1524)
				)
			)
		)
		(duplicate_pad_numbers_are_jumpers no)
		(fp_line
			(start 0.635 0)
			(end -0.635 0)
			(stroke
				(width 0.508)
				(type default)
			)
			(layer "F.SilkS")
		)
		(fp_rect
			(start -0.9652 1.778)
			(end 0.9652 -1.778)
			(stroke
				(width 0)
				(type default)
			)
			(fill no)
			(layer "F.CrtYd")
		)
		(fp_poly
			(pts
				(xy -0.9652 -1.778) (xy 0.9652 -1.778) (xy 0.9652 1.778) (xy -0.9652 1.778)
			)
			(stroke
				(width 0)
				(type default)
			)
			(fill no)
			(layer "F.Fab")
		)
		(pad "1" smd rect
			(at 0 -0.9652 180)
			(size 1.397 1.143)
			(layers "F.Cu" "F.Mask" "F.Paste")
			(net "P12V_HDD31")
		)
		(pad "2" smd rect
			(at 0 0.9652 180)
			(size 1.397 1.143)
			(layers "F.Cu" "F.Mask" "F.Paste")
			(net "GND")
		)
	)
	(footprint ""
		(layer "F.Cu")
		(at 231.267 -196.596 -90)
		(property "Reference" "R76"
			(at 0 0 270)
			(layer "F.SilkS")
			(hide yes)
			(effects
				(font
					(size 1.27 1.27)
				)
			)
		)
		(property "Value" "0R2J-2-GP"
			(at 0.064008 -3.993896 270)
			(unlocked yes)
			(layer "F.Fab")
			(hide yes)
			(effects
				(font
					(size 1.016 1.016)
					(thickness 0.1524)
				)
			)
		)
		(property "Device Type" "R402H16"
			(at 0.064008 -5.517896 270)
			(unlocked yes)
			(layer "F.Fab")
			(hide yes)
			(effects
				(font
					(size 1.016 1.016)
					(thickness 0.1524)
				)
			)
		)
		(duplicate_pad_numbers_are_jumpers no)
		(fp_line
			(start -0.508 -0.9398)
			(end -0.508 0.9398)
			(stroke
				(width 0.1524)
				(type default)
			)
			(layer "F.SilkS")
		)
		(fp_line
			(start 0.508 -0.9398)
			(end -0.508 -0.9398)
			(stroke
				(width 0.1524)
				(type default)
			)
			(layer "F.SilkS")
		)
		(fp_rect
			(start -0.508 0.9398)
			(end 0.508 -0.9398)
			(stroke
				(width 0)
				(type default)
			)
			(fill no)
			(layer "F.CrtYd")
		)
		(fp_rect
			(start -0.508 0.9398)
			(end 0.508 -0.9398)
			(stroke
				(width 0)
				(type default)
			)
			(fill no)
			(layer "F.Fab")
		)
		(pad "1" smd custom
			(at 0 -0.4445 270)
			(size 0.1397 0.1397)
			(layers "F.Cu" "F.Mask" "F.Paste")
			(net "IO_EXP2_SCL")
			(options
				(clearance outline)
				(anchor circle)
			)
			(primitives
				(gr_poly
					(pts
						(arc
							(start -0.1778 -0.2794)
							(mid -0.249642 -0.249642)
							(end -0.2794 -0.1778)
						)
						(arc
							(start -0.2794 0.1778)
							(mid -0.249642 0.249642)
							(end -0.1778 0.2794)
						)
						(arc
							(start 0.1778 0.2794)
							(mid 0.249642 0.249642)
							(end 0.2794 0.1778)
						)
						(arc
							(start 0.2794 -0.1778)
							(mid 0.249642 -0.249642)
							(end 0.1778 -0.2794)
						)
					)
					(width 0)
					(fill yes)
				)
			)
		)
		(pad "2" smd custom
			(at 0 0.4445 270)
			(size 0.1397 0.1397)
			(layers "F.Cu" "F.Mask" "F.Paste")
			(net "I2C_DRIVE_B_PWR_SCL")
			(options
				(clearance outline)
				(anchor circle)
			)
			(primitives
				(gr_poly
					(pts
						(arc
							(start -0.1778 -0.2794)
							(mid -0.249642 -0.249642)
							(end -0.2794 -0.1778)
						)
						(arc
							(start -0.2794 0.1778)
							(mid -0.249642 0.249642)
							(end -0.1778 0.2794)
						)
						(arc
							(start 0.1778 0.2794)
							(mid 0.249642 0.249642)
							(end 0.2794 0.1778)
						)
						(arc
							(start 0.2794 -0.1778)
							(mid 0.249642 -0.249642)
							(end 0.1778 -0.2794)
						)
					)
					(width 0)
					(fill yes)
				)
			)
		)
	)
	(footprint ""
		(layer "F.Cu")
		(at 459.7908 -270.5862 -90)
		(property "Reference" "R320"
			(at 0 0 270)
			(layer "F.SilkS")
			(hide yes)
			(effects
				(font
					(size 1.27 1.27)
				)
			)
		)
		(property "Value" "2R6F-GP"
			(at -0.0508 -4.8514 270)
			(unlocked yes)
			(layer "F.Fab")
			(hide yes)
			(effects
				(font
					(size 1.016 1.016)
					(thickness 0.1524)
				)
			)
		)
		(property "Device Type" "R1206H26"
			(at 0 -6.3754 270)
			(unlocked yes)
			(layer "F.Fab")
			(hide yes)
			(effects
				(font
					(size 1.016 1.016)
					(thickness 0.1524)
				)
			)
		)
		(duplicate_pad_numbers_are_jumpers no)
		(fp_line
			(start -1.016 2.2352)
			(end -1.016 -2.2352)
			(stroke
				(width 0.1524)
				(type default)
			)
			(layer "F.SilkS")
		)
		(fp_line
			(start 1.016 2.2352)
			(end -1.016 2.2352)
			(stroke
				(width 0.1524)
				(type default)
			)
			(layer "F.SilkS")
		)
		(fp_line
			(start -1.016 -2.2352)
			(end 1.016 -2.2352)
			(stroke
				(width 0.1524)
				(type default)
			)
			(layer "F.SilkS")
		)
		(fp_line
			(start 1.016 -2.2352)
			(end 1.016 2.2352)
			(stroke
				(width 0.1524)
				(type default)
			)
			(layer "F.SilkS")
		)
		(fp_rect
			(start -1.0922 2.3114)
			(end 1.0922 -2.3114)
			(stroke
				(width 0)
				(type default)
			)
			(fill no)
			(layer "F.CrtYd")
		)
		(fp_poly
			(pts
				(xy -1.0922 -2.3114) (xy 1.0922 -2.3114) (xy 1.0922 2.3114) (xy -1.0922 2.3114)
			)
			(stroke
				(width 0)
				(type default)
			)
			(fill no)
			(layer "F.Fab")
		)
		(pad "1" smd rect
			(at 0 -1.397 270)
			(size 1.651 1.27)
			(layers "F.Cu" "F.Mask" "F.Paste")
			(net "P12V_HDD10")
		)
		(pad "2" smd rect
			(at 0 1.397 270)
			(size 1.651 1.27)
			(layers "F.Cu" "F.Mask" "F.Paste")
			(net "12V_PRE_10")
		)
	)
	(footprint ""
		(layer "F.Cu")
		(at 79.883 -138.049 90)
		(property "Reference" "R399"
			(at 0 0 90)
			(layer "F.SilkS")
			(hide yes)
			(effects
				(font
					(size 1.27 1.27)
				)
			)
		)
		(property "Value" "4K7R2J-2-GP"
			(at 0.064008 -3.993896 90)
			(unlocked yes)
			(layer "F.Fab")
			(hide yes)
			(effects
				(font
					(size 1.016 1.016)
					(thickness 0.1524)
				)
			)
		)
		(property "Device Type" "R402H16"
			(at 0.064008 -5.517896 90)
			(unlocked yes)
			(layer "F.Fab")
			(hide yes)
			(effects
				(font
					(size 1.016 1.016)
					(thickness 0.1524)
				)
			)
		)
		(duplicate_pad_numbers_are_jumpers no)
		(fp_line
			(start 0.508 -0.9398)
			(end -0.508 -0.9398)
			(stroke
				(width 0.1524)
				(type default)
			)
			(layer "F.SilkS")
		)
		(fp_line
			(start -0.508 -0.9398)
			(end -0.508 0.9398)
			(stroke
				(width 0.1524)
				(type default)
			)
			(layer "F.SilkS")
		)
		(fp_rect
			(start -0.508 0.9398)
			(end 0.508 -0.9398)
			(stroke
				(width 0)
				(type default)
			)
			(fill no)
			(layer "F.CrtYd")
		)
		(fp_rect
			(start -0.508 0.9398)
			(end 0.508 -0.9398)
			(stroke
				(width 0)
				(type default)
			)
			(fill no)
			(layer "F.Fab")
		)
		(pad "1" smd custom
			(at 0 -0.4445 90)
			(size 0.1397 0.1397)
			(layers "F.Cu" "F.Mask" "F.Paste")
			(net "P12V_B")
			(options
				(clearance outline)
				(anchor circle)
			)
			(primitives
				(gr_poly
					(pts
						(arc
							(start -0.1778 -0.2794)
							(mid -0.249642 -0.249642)
							(end -0.2794 -0.1778)
						)
						(arc
							(start -0.2794 0.1778)
							(mid -0.249642 0.249642)
							(end -0.1778 0.2794)
						)
						(arc
							(start 0.1778 0.2794)
							(mid 0.249642 0.249642)
							(end 0.2794 0.1778)
						)
						(arc
							(start 0.2794 -0.1778)
							(mid 0.249642 -0.249642)
							(end 0.1778 -0.2794)
						)
					)
					(width 0)
					(fill yes)
				)
			)
		)
		(pad "2" smd custom
			(at 0 0.4445 90)
			(size 0.1397 0.1397)
			(layers "F.Cu" "F.Mask" "F.Paste")
			(net "SW_HDD_P14")
			(options
				(clearance outline)
				(anchor circle)
			)
			(primitives
				(gr_poly
					(pts
						(arc
							(start -0.1778 -0.2794)
							(mid -0.249642 -0.249642)
							(end -0.2794 -0.1778)
						)
						(arc
							(start -0.2794 0.1778)
							(mid -0.249642 0.249642)
							(end -0.1778 0.2794)
						)
						(arc
							(start 0.1778 0.2794)
							(mid 0.249642 0.249642)
							(end 0.2794 0.1778)
						)
						(arc
							(start 0.2794 -0.1778)
							(mid 0.249642 -0.249642)
							(end 0.1778 -0.2794)
						)
					)
					(width 0)
					(fill yes)
				)
			)
		)
	)
	(footprint ""
		(layer "F.Cu")
		(at 129.921 -263.144 -90)
		(property "Reference" "R207"
			(at 0 0 270)
			(layer "F.SilkS")
			(hide yes)
			(effects
				(font
					(size 1.27 1.27)
				)
			)
		)
		(property "Value" "10KR2F-2-GP"
			(at 0.064008 -3.993896 270)
			(unlocked yes)
			(layer "F.Fab")
			(hide yes)
			(effects
				(font
					(size 1.016 1.016)
					(thickness 0.1524)
				)
			)
		)
		(property "Device Type" "R402H16"
			(at 0.064008 -5.517896 270)
			(unlocked yes)
			(layer "F.Fab")
			(hide yes)
			(effects
				(font
					(size 1.016 1.016)
					(thickness 0.1524)
				)
			)
		)
		(duplicate_pad_numbers_are_jumpers no)
		(fp_line
			(start -0.508 -0.9398)
			(end -0.508 0.9398)
			(stroke
				(width 0.1524)
				(type default)
			)
			(layer "F.SilkS")
		)
		(fp_line
			(start 0.508 -0.9398)
			(end -0.508 -0.9398)
			(stroke
				(width 0.1524)
				(type default)
			)
			(layer "F.SilkS")
		)
		(fp_rect
			(start -0.508 0.9398)
			(end 0.508 -0.9398)
			(stroke
				(width 0)
				(type default)
			)
			(fill no)
			(layer "F.CrtYd")
		)
		(fp_rect
			(start -0.508 0.9398)
			(end 0.508 -0.9398)
			(stroke
				(width 0)
				(type default)
			)
			(fill no)
			(layer "F.Fab")
		)
		(pad "1" smd custom
			(at 0 -0.4445 270)
			(size 0.1397 0.1397)
			(layers "F.Cu" "F.Mask" "F.Paste")
			(net "P3V3_STBY_B")
			(options
				(clearance outline)
				(anchor circle)
			)
			(primitives
				(gr_poly
					(pts
						(arc
							(start -0.1778 -0.2794)
							(mid -0.249642 -0.249642)
							(end -0.2794 -0.1778)
						)
						(arc
							(start -0.2794 0.1778)
							(mid -0.249642 0.249642)
							(end -0.1778 0.2794)
						)
						(arc
							(start 0.1778 0.2794)
							(mid 0.249642 0.249642)
							(end 0.2794 0.1778)
						)
						(arc
							(start 0.2794 -0.1778)
							(mid 0.249642 -0.249642)
							(end 0.1778 -0.2794)
						)
					)
					(width 0)
					(fill yes)
				)
			)
		)
		(pad "2" smd custom
			(at 0 0.4445 270)
			(size 0.1397 0.1397)
			(layers "F.Cu" "F.Mask" "F.Paste")
			(net "HDD_PRSNT_3")
			(options
				(clearance outline)
				(anchor circle)
			)
			(primitives
				(gr_poly
					(pts
						(arc
							(start -0.1778 -0.2794)
							(mid -0.249642 -0.249642)
							(end -0.2794 -0.1778)
						)
						(arc
							(start -0.2794 0.1778)
							(mid -0.249642 0.249642)
							(end -0.1778 0.2794)
						)
						(arc
							(start 0.1778 0.2794)
							(mid 0.249642 0.249642)
							(end 0.2794 0.1778)
						)
						(arc
							(start 0.2794 -0.1778)
							(mid 0.249642 -0.249642)
							(end 0.1778 -0.2794)
						)
					)
					(width 0)
					(fill yes)
				)
			)
		)
	)
	(footprint ""
		(layer "F.Cu")
		(at 331.4954 -135.636 -90)
		(property "Reference" "C272"
			(at 0 0 270)
			(layer "F.SilkS")
			(hide yes)
			(effects
				(font
					(size 1.27 1.27)
				)
			)
		)
		(property "Value" "SCD033U25V2KX-GP"
			(at 1.1811 -2.7051 270)
			(unlocked yes)
			(layer "F.Fab")
			(hide yes)
			(effects
				(font
					(size 1.016 1.016)
					(thickness 0.1524)
				)
			)
		)
		(property "Device Type" "C402H22"
			(at 1.1811 -4.2291 270)
			(unlocked yes)
			(layer "F.Fab")
			(hide yes)
			(effects
				(font
					(size 1.016 1.016)
					(thickness 0.1524)
				)
			)
		)
		(duplicate_pad_numbers_are_jumpers no)
		(fp_rect
			(start -0.4318 0.9525)
			(end 0.4318 -0.9525)
			(stroke
				(width 0)
				(type default)
			)
			(fill no)
			(layer "F.CrtYd")
		)
		(fp_rect
			(start -0.4318 0.9525)
			(end 0.4318 -0.9525)
			(stroke
				(width 0)
				(type default)
			)
			(fill no)
			(layer "F.Fab")
		)
		(pad "1" smd custom
			(at 0 -0.4445 270)
			(size 0.1524 0.1524)
			(layers "F.Cu" "F.Mask" "F.Paste")
			(net "SW_HDD_P18")
			(options
				(clearance outline)
				(anchor circle)
			)
			(primitives
				(gr_poly
					(pts
						(arc
							(start 0.3048 -0.2032)
							(mid 0.275042 -0.275042)
							(end 0.2032 -0.3048)
						)
						(arc
							(start -0.2032 -0.3048)
							(mid -0.275042 -0.275042)
							(end -0.3048 -0.2032)
						)
						(arc
							(start -0.3048 0.2032)
							(mid -0.275042 0.275042)
							(end -0.2032 0.3048)
						)
						(arc
							(start 0.2032 0.3048)
							(mid 0.275042 0.275042)
							(end 0.3048 0.2032)
						)
					)
					(width 0)
					(fill yes)
				)
			)
		)
		(pad "2" smd custom
			(at 0 0.4445 270)
			(size 0.1524 0.1524)
			(layers "F.Cu" "F.Mask" "F.Paste")
			(net "GND")
			(options
				(clearance outline)
				(anchor circle)
			)
			(primitives
				(gr_poly
					(pts
						(arc
							(start 0.3048 -0.2032)
							(mid 0.275042 -0.275042)
							(end 0.2032 -0.3048)
						)
						(arc
							(start -0.2032 -0.3048)
							(mid -0.275042 -0.275042)
							(end -0.3048 -0.2032)
						)
						(arc
							(start -0.3048 0.2032)
							(mid -0.275042 0.275042)
							(end -0.2032 0.3048)
						)
						(arc
							(start 0.2032 0.3048)
							(mid 0.275042 0.275042)
							(end 0.3048 0.2032)
						)
					)
					(width 0)
					(fill yes)
				)
			)
		)
	)
)
